Test item Owner Result Comments Check
steps
Estimated time Automated
BIOS version name: Pass Follow BIOS naming rule v2.0.
This BIOS had synced with latest IBV (e.g.: AMI)
CRB label (XYZ).
Harris Pass BIOS development in NPI phase should sync with latest
AMI CRB label.
This BIOS had included latest microcode. Harris Pass BIOS should always include latest microcode.
This BIOS had synced with latest silicon
reference code (MRC, PPM, RAS...) from IBV
(e.g.: AMI).
Harris Pass BIOS development in NPI phase should sync with latest
AMI silicon emodule.
BIOS Specification had updated to sync with
current BIOS.
Harris Pass BIOS specification (XXX) is updated to sync with current
BIOS.
Boot with 2 Processor (Optional) Harris Pass
Boot with 4 Processor Harris Pass
      Setup menu information: CPU 1/2 Harris Pass
      OS information: CPU 1/2 Harris Pass
Memory – Full Config Harris Pass Configuration:
24 * Samsung
Memory – Minimum Config (Optional) Harris Pass
LV DIMM running at 1.35V/1.2V (Optional) Harris None
USB Boot UEFI Harris Pass
Boot into BIOS Setup Harris Pass
EFI Shell Boot Harris Pass
      File system fs0 using USB Key Harris Pass 2 mins
      Commands – ls, map –r Harris Pass 2 mins
      Exit brings back to setup Harris Pass 2 mins
Windows P1 OS:  (per MKT) None OS name:
     Install None Configuration:
- MB:
- CPU:
- Memory:
- HDD storage:
- BMC version:
60 mins
     Boot None 5 mins
     Device Manager – No Yellow Marks None 2 mins
BIOS Pre-Release Test Report



     All Onchip Devices Detected None 2 mins
     All Onboard Devices Detected None 2 mins
     Shutdown and restart None 5 mins
Linux P1 OS:  (per MKT) OS name:CentOS 8 Stream, Kernel 5.19.0-
0_fbk4_zion_10711_g9cbb08e4dfe0 on an x86_64
     Install Harris Pass 60 mins
     Boot Harris Pass 5 mins
    Shutdown and restart Harris Pass 5 mins
    No error reports from "dmesg | grep error -i" Harris Pass 2mins
Linux OS DC cycle (1 hour) Harris Pass  OS name/SVN revision:
BIOS update via Utility
     UEFI -  AFUEFI Harris None AFU version: 10 mins
     Linux -  AFULNX Harris Pass AFU version:v5.15.03.0081 10 mins
     Windows -  AFUWIN Harris None AFU version: 10 mins
BIOS Recovery (Jumper)  (Optional) Harris None
Setup Server Management and System
Information
     BMC FW Version (SMBIOS) Harris Pass 2023.19.1 2 mins
     FRUSDR Version  (SMBIOS) Harris None 2 mins
     ME Information Harris None 2 mins
Console Redirection (Enable/Disable) Harris Pass Enable 5 mins
BIOS Debug_Mode disable Harris Pass
BIOS Debug_Mode Enabled: Harris Pass
1. save Debug message to folder "Released
BIOS Source Code / [Release version]".
2. Boot with Debug_mode enabled: message
w/o assert.
Harris Pass
Compare SCE dump to check any default/map
changed.
Harris Pass SCE version: SCELNX64_v5.05.06.0007
Any changed:
run_script w/o unexpected error Harris Pass
The same BIOS to dump PCR0 for different
DCD/DBI
Compare Slot ID/BDF to align with SMBIOS
Type9, Lspci and Debug Runbook
Harris Pass GT-Inference Debug Runbook_Quanta_share_202300316